(kicad_pcb
	(version 20260206)
	(generator "pcbnew")
	(generator_version "10.0")
	(general
		(thickness 1.6)
		(legacy_teardrops no)
	)
	(paper "A4")
	(title_block
		(title "04192023_DAF0TMB3IC0_F0TG_MB_C_brd_V02_OCP.brd")
		(comment 1 "Grand Teton / footprints 7967-7972 of 8354")
	)
	(layers
		(0 "F.Cu" signal "TOP")
		(4 "In1.Cu" signal "GND")
		(6 "In2.Cu" signal "IN1")
		(8 "In3.Cu" signal "GND1")
		(10 "In4.Cu" signal "IN2")
		(12 "In5.Cu" signal "GND2")
		(14 "In6.Cu" signal "IN3")
		(16 "In7.Cu" signal "GND3")
		(18 "In8.Cu" signal "VCC")
		(20 "In9.Cu" signal "VCC1")
		(22 "In10.Cu" signal "GND4")
		(24 "In11.Cu" signal "IN4")
		(26 "In12.Cu" signal "GND5")
		(28 "In13.Cu" signal "IN5")
		(30 "In14.Cu" signal "GND6")
		(32 "In15.Cu" signal "IN6")
		(34 "In16.Cu" signal "GND7")
		(2 "B.Cu" signal "BOTTOM")
		(9 "F.Adhes" user "F.Adhesive")
		(11 "B.Adhes" user "B.Adhesive")
		(13 "F.Paste" user "Package Geometry/Pastemask Top")
		(15 "B.Paste" user "Package Geometry/Pastemask Bottom")
		(5 "F.SilkS" user "Ref Des/Silkscreen Top")
		(7 "B.SilkS" user "Ref Des/Silkscreen Bottom")
		(1 "F.Mask" user "Board Geometry/Soldermask Top")
		(3 "B.Mask" user "Board Geometry/Soldermask Bottom")
		(17 "Dwgs.User" user "User.Drawings")
		(19 "Cmts.User" user "User.Comments")
		(21 "Eco1.User" user "User.Eco1")
		(23 "Eco2.User" user "User.Eco2")
		(25 "Edge.Cuts" user "Board Geometry/Outline")
		(27 "Margin" user)
		(31 "F.CrtYd" user "Package Geometry/Place Bound Top")
		(29 "B.CrtYd" user "Package Geometry/Place Bound Bottom")
		(35 "F.Fab" user "Ref Des/Assembly Top")
		(33 "B.Fab" user "Ref Des/Assembly Bottom")
	)
	(footprint ""
		(layer "B.Cu")
		(at 167.39743 -105.755694 90)
		(property "Reference" "R11"
			(at 0 0 90)
			(layer "B.SilkS")
			(hide yes)
			(effects
				(font
					(size 1.27 1.27)
				)
				(justify mirror)
			)
		)
		(property "Value" ""
			(at 0 0 90)
			(layer "B.Fab")
			(effects
				(font
					(size 1.27 1.27)
				)
				(justify mirror)
			)
		)
		(duplicate_pad_numbers_are_jumpers no)
		(fp_line
			(start 0.7874 -0.4064)
			(end -0.7874 -0.4064)
			(stroke
				(width 0.1524)
				(type default)
			)
			(layer "B.SilkS")
		)
		(fp_line
			(start -0.7874 -0.4064)
			(end -0.7874 0.4064)
			(stroke
				(width 0.1524)
				(type default)
			)
			(layer "B.SilkS")
		)
		(fp_line
			(start 0.7874 0.4064)
			(end 0.7874 -0.4064)
			(stroke
				(width 0.1524)
				(type default)
			)
			(layer "B.SilkS")
		)
		(fp_line
			(start -0.7874 0.4064)
			(end 0.7874 0.4064)
			(stroke
				(width 0.1524)
				(type default)
			)
			(layer "B.SilkS")
		)
		(fp_line
			(start 0.67945 -0.305054)
			(end 0.12065 -0.305054)
			(stroke
				(width 0.1)
				(type default)
			)
			(layer "B.Fab")
		)
		(fp_line
			(start 0.12065 -0.305054)
			(end 0.12065 -0.2794)
			(stroke
				(width 0.1)
				(type default)
			)
			(layer "B.Fab")
		)
		(fp_line
			(start -0.12065 -0.3048)
			(end -0.67945 -0.3048)
			(stroke
				(width 0.1)
				(type default)
			)
			(layer "B.Fab")
		)
		(fp_line
			(start -0.67945 -0.3048)
			(end -0.67945 0.3048)
			(stroke
				(width 0.1)
				(type default)
			)
			(layer "B.Fab")
		)
		(fp_line
			(start 0.12065 -0.2794)
			(end -0.12065 -0.2794)
			(stroke
				(width 0.1)
				(type default)
			)
			(layer "B.Fab")
		)
		(fp_line
			(start -0.12065 -0.2794)
			(end -0.12065 -0.3048)
			(stroke
				(width 0.1)
				(type default)
			)
			(layer "B.Fab")
		)
		(fp_line
			(start 0.12065 0.2794)
			(end 0.12065 0.3048)
			(stroke
				(width 0.1)
				(type default)
			)
			(layer "B.Fab")
		)
		(fp_line
			(start -0.120396 0.2794)
			(end 0.12065 0.2794)
			(stroke
				(width 0.1)
				(type default)
			)
			(layer "B.Fab")
		)
		(fp_line
			(start 0.67945 0.3048)
			(end 0.67945 -0.305054)
			(stroke
				(width 0.1)
				(type default)
			)
			(layer "B.Fab")
		)
		(fp_line
			(start 0.12065 0.3048)
			(end 0.67945 0.3048)
			(stroke
				(width 0.1)
				(type default)
			)
			(layer "B.Fab")
		)
		(fp_line
			(start -0.120396 0.3048)
			(end -0.120396 0.2794)
			(stroke
				(width 0.1)
				(type default)
			)
			(layer "B.Fab")
		)
		(fp_line
			(start -0.67945 0.3048)
			(end -0.120396 0.3048)
			(stroke
				(width 0.1)
				(type default)
			)
			(layer "B.Fab")
		)
		(pad "1" smd circle
			(at 0.40005 0 270)
			(size 0 0)
			(layers "B.Cu" "B.Mask" "B.Paste")
			(net "FM_I3C_CPU0_MUX1_OE_N")
		)
		(pad "2" smd circle
			(at -0.40005 0 270)
			(size 0 0)
			(layers "B.Cu" "B.Mask" "B.Paste")
			(net "GND")
		)
	)
	(footprint ""
		(layer "B.Cu")
		(at 116.116354 -415.910268 90)
		(property "Reference" "C1988"
			(at 0 0 90)
			(layer "B.SilkS")
			(hide yes)
			(effects
				(font
					(size 1.27 1.27)
				)
				(justify mirror)
			)
		)
		(property "Value" ""
			(at 0 0 90)
			(layer "B.Fab")
			(effects
				(font
					(size 1.27 1.27)
				)
				(justify mirror)
			)
		)
		(duplicate_pad_numbers_are_jumpers no)
		(fp_line
			(start 0.7874 -0.4064)
			(end -0.7874 -0.4064)
			(stroke
				(width 0.1524)
				(type default)
			)
			(layer "B.SilkS")
		)
		(fp_line
			(start -0.7874 -0.4064)
			(end -0.7874 0.4064)
			(stroke
				(width 0.1524)
				(type default)
			)
			(layer "B.SilkS")
		)
		(fp_line
			(start 0.7874 0.4064)
			(end 0.7874 -0.4064)
			(stroke
				(width 0.1524)
				(type default)
			)
			(layer "B.SilkS")
		)
		(fp_line
			(start -0.7874 0.4064)
			(end 0.7874 0.4064)
			(stroke
				(width 0.1524)
				(type default)
			)
			(layer "B.SilkS")
		)
		(fp_line
			(start 0.67945 -0.305054)
			(end 0.12065 -0.305054)
			(stroke
				(width 0.1)
				(type default)
			)
			(layer "B.Fab")
		)
		(fp_line
			(start 0.12065 -0.305054)
			(end 0.12065 -0.2794)
			(stroke
				(width 0.1)
				(type default)
			)
			(layer "B.Fab")
		)
		(fp_line
			(start -0.12065 -0.3048)
			(end -0.67945 -0.3048)
			(stroke
				(width 0.1)
				(type default)
			)
			(layer "B.Fab")
		)
		(fp_line
			(start -0.67945 -0.3048)
			(end -0.67945 0.3048)
			(stroke
				(width 0.1)
				(type default)
			)
			(layer "B.Fab")
		)
		(fp_line
			(start 0.12065 -0.2794)
			(end -0.12065 -0.2794)
			(stroke
				(width 0.1)
				(type default)
			)
			(layer "B.Fab")
		)
		(fp_line
			(start -0.12065 -0.2794)
			(end -0.12065 -0.3048)
			(stroke
				(width 0.1)
				(type default)
			)
			(layer "B.Fab")
		)
		(fp_line
			(start 0.12065 0.2794)
			(end 0.12065 0.3048)
			(stroke
				(width 0.1)
				(type default)
			)
			(layer "B.Fab")
		)
		(fp_line
			(start -0.120396 0.2794)
			(end 0.12065 0.2794)
			(stroke
				(width 0.1)
				(type default)
			)
			(layer "B.Fab")
		)
		(fp_line
			(start 0.67945 0.3048)
			(end 0.67945 -0.305054)
			(stroke
				(width 0.1)
				(type default)
			)
			(layer "B.Fab")
		)
		(fp_line
			(start 0.12065 0.3048)
			(end 0.67945 0.3048)
			(stroke
				(width 0.1)
				(type default)
			)
			(layer "B.Fab")
		)
		(fp_line
			(start -0.120396 0.3048)
			(end -0.120396 0.2794)
			(stroke
				(width 0.1)
				(type default)
			)
			(layer "B.Fab")
		)
		(fp_line
			(start -0.67945 0.3048)
			(end -0.120396 0.3048)
			(stroke
				(width 0.1)
				(type default)
			)
			(layer "B.Fab")
		)
		(pad "1" smd circle
			(at 0.40005 0 270)
			(size 0 0)
			(layers "B.Cu" "B.Mask" "B.Paste")
			(net "GPU_FPGA_EROT_FATALERR_ISO_N")
		)
		(pad "2" smd circle
			(at -0.40005 0 270)
			(size 0 0)
			(layers "B.Cu" "B.Mask" "B.Paste")
			(net "GND")
		)
	)
	(footprint ""
		(layer "B.Cu")
		(at 85.919056 -390.560052 90)
		(property "Reference" "C338"
			(at 0 0 90)
			(layer "B.SilkS")
			(hide yes)
			(effects
				(font
					(size 1.27 1.27)
				)
				(justify mirror)
			)
		)
		(property "Value" ""
			(at 0 0 90)
			(layer "B.Fab")
			(effects
				(font
					(size 1.27 1.27)
				)
				(justify mirror)
			)
		)
		(duplicate_pad_numbers_are_jumpers no)
		(fp_line
			(start 0.7874 -0.4064)
			(end -0.7874 -0.4064)
			(stroke
				(width 0.1524)
				(type default)
			)
			(layer "B.SilkS")
		)
		(fp_line
			(start -0.7874 -0.4064)
			(end -0.7874 0.4064)
			(stroke
				(width 0.1524)
				(type default)
			)
			(layer "B.SilkS")
		)
		(fp_line
			(start 0.7874 0.4064)
			(end 0.7874 -0.4064)
			(stroke
				(width 0.1524)
				(type default)
			)
			(layer "B.SilkS")
		)
		(fp_line
			(start -0.7874 0.4064)
			(end 0.7874 0.4064)
			(stroke
				(width 0.1524)
				(type default)
			)
			(layer "B.SilkS")
		)
		(fp_line
			(start 0.67945 -0.305054)
			(end 0.12065 -0.305054)
			(stroke
				(width 0.1)
				(type default)
			)
			(layer "B.Fab")
		)
		(fp_line
			(start 0.12065 -0.305054)
			(end 0.12065 -0.2794)
			(stroke
				(width 0.1)
				(type default)
			)
			(layer "B.Fab")
		)
		(fp_line
			(start -0.12065 -0.3048)
			(end -0.67945 -0.3048)
			(stroke
				(width 0.1)
				(type default)
			)
			(layer "B.Fab")
		)
		(fp_line
			(start -0.67945 -0.3048)
			(end -0.67945 0.3048)
			(stroke
				(width 0.1)
				(type default)
			)
			(layer "B.Fab")
		)
		(fp_line
			(start 0.12065 -0.2794)
			(end -0.12065 -0.2794)
			(stroke
				(width 0.1)
				(type default)
			)
			(layer "B.Fab")
		)
		(fp_line
			(start -0.12065 -0.2794)
			(end -0.12065 -0.3048)
			(stroke
				(width 0.1)
				(type default)
			)
			(layer "B.Fab")
		)
		(fp_line
			(start 0.12065 0.2794)
			(end 0.12065 0.3048)
			(stroke
				(width 0.1)
				(type default)
			)
			(layer "B.Fab")
		)
		(fp_line
			(start -0.120396 0.2794)
			(end 0.12065 0.2794)
			(stroke
				(width 0.1)
				(type default)
			)
			(layer "B.Fab")
		)
		(fp_line
			(start 0.67945 0.3048)
			(end 0.67945 -0.305054)
			(stroke
				(width 0.1)
				(type default)
			)
			(layer "B.Fab")
		)
		(fp_line
			(start 0.12065 0.3048)
			(end 0.67945 0.3048)
			(stroke
				(width 0.1)
				(type default)
			)
			(layer "B.Fab")
		)
		(fp_line
			(start -0.120396 0.3048)
			(end -0.120396 0.2794)
			(stroke
				(width 0.1)
				(type default)
			)
			(layer "B.Fab")
		)
		(fp_line
			(start -0.67945 0.3048)
			(end -0.120396 0.3048)
			(stroke
				(width 0.1)
				(type default)
			)
			(layer "B.Fab")
		)
		(pad "1" smd circle
			(at 0.40005 0 270)
			(size 0 0)
			(layers "B.Cu" "B.Mask" "B.Paste")
			(net "P0V9_CPU1_RT_2D")
		)
		(pad "2" smd circle
			(at -0.40005 0 270)
			(size 0 0)
			(layers "B.Cu" "B.Mask" "B.Paste")
			(net "GND")
		)
	)
	(footprint ""
		(layer "B.Cu")
		(at 381.192786 -214.523828 90)
		(property "Reference" "R8563"
			(at 0 0 90)
			(layer "B.SilkS")
			(hide yes)
			(effects
				(font
					(size 1.27 1.27)
				)
				(justify mirror)
			)
		)
		(property "Value" ""
			(at 0 0 90)
			(layer "B.Fab")
			(effects
				(font
					(size 1.27 1.27)
				)
				(justify mirror)
			)
		)
		(duplicate_pad_numbers_are_jumpers no)
		(fp_line
			(start 0.436372 -0.4064)
			(end -0.325628 -0.4064)
			(stroke
				(width 0.1524)
				(type default)
			)
			(layer "B.SilkS")
		)
		(fp_line
			(start -0.7874 0.061214)
			(end -0.7874 0.4064)
			(stroke
				(width 0.1524)
				(type default)
			)
			(layer "B.SilkS")
		)
		(fp_line
			(start 0.7874 0.4064)
			(end 0.7874 -0.014986)
			(stroke
				(width 0.1524)
				(type default)
			)
			(layer "B.SilkS")
		)
		(fp_line
			(start -0.7874 0.4064)
			(end 0.7874 0.4064)
			(stroke
				(width 0.1524)
				(type default)
			)
			(layer "B.SilkS")
		)
		(fp_line
			(start 0.67945 -0.305054)
			(end 0.12065 -0.305054)
			(stroke
				(width 0.1)
				(type default)
			)
			(layer "B.Fab")
		)
		(fp_line
			(start 0.12065 -0.305054)
			(end 0.12065 -0.2794)
			(stroke
				(width 0.1)
				(type default)
			)
			(layer "B.Fab")
		)
		(fp_line
			(start -0.12065 -0.3048)
			(end -0.67945 -0.3048)
			(stroke
				(width 0.1)
				(type default)
			)
			(layer "B.Fab")
		)
		(fp_line
			(start -0.67945 -0.3048)
			(end -0.67945 0.3048)
			(stroke
				(width 0.1)
				(type default)
			)
			(layer "B.Fab")
		)
		(fp_line
			(start 0.12065 -0.2794)
			(end -0.12065 -0.2794)
			(stroke
				(width 0.1)
				(type default)
			)
			(layer "B.Fab")
		)
		(fp_line
			(start -0.12065 -0.2794)
			(end -0.12065 -0.3048)
			(stroke
				(width 0.1)
				(type default)
			)
			(layer "B.Fab")
		)
		(fp_line
			(start 0.12065 0.2794)
			(end 0.12065 0.3048)
			(stroke
				(width 0.1)
				(type default)
			)
			(layer "B.Fab")
		)
		(fp_line
			(start -0.120396 0.2794)
			(end 0.12065 0.2794)
			(stroke
				(width 0.1)
				(type default)
			)
			(layer "B.Fab")
		)
		(fp_line
			(start 0.67945 0.3048)
			(end 0.67945 -0.305054)
			(stroke
				(width 0.1)
				(type default)
			)
			(layer "B.Fab")
		)
		(fp_line
			(start 0.12065 0.3048)
			(end 0.67945 0.3048)
			(stroke
				(width 0.1)
				(type default)
			)
			(layer "B.Fab")
		)
		(fp_line
			(start -0.120396 0.3048)
			(end -0.120396 0.2794)
			(stroke
				(width 0.1)
				(type default)
			)
			(layer "B.Fab")
		)
		(fp_line
			(start -0.67945 0.3048)
			(end -0.120396 0.3048)
			(stroke
				(width 0.1)
				(type default)
			)
			(layer "B.Fab")
		)
		(pad "1" smd circle
			(at 0.40005 0 270)
			(size 0 0)
			(layers "B.Cu" "B.Mask" "B.Paste")
			(net "CLK_100M_CPU0_CLK02_R_DP")
		)
		(pad "2" smd circle
			(at -0.40005 0 270)
			(size 0 0)
			(layers "B.Cu" "B.Mask" "B.Paste")
			(net "CLK_100M_CPU0_CLK02_DP")
		)
	)
	(footprint ""
		(layer "B.Cu")
		(at 364.788958 -272.284952)
		(property "Reference" "C2221"
			(at 0 0 0)
			(layer "B.SilkS")
			(hide yes)
			(effects
				(font
					(size 1.27 1.27)
				)
				(justify mirror)
			)
		)
		(property "Value" ""
			(at 0 0 0)
			(layer "B.Fab")
			(effects
				(font
					(size 1.27 1.27)
				)
				(justify mirror)
			)
		)
		(duplicate_pad_numbers_are_jumpers no)
		(fp_line
			(start -0.7874 -0.4064)
			(end -0.7874 0.4064)
			(stroke
				(width 0.1524)
				(type default)
			)
			(layer "B.SilkS")
		)
		(fp_line
			(start -0.7874 0.4064)
			(end 0.7874 0.4064)
			(stroke
				(width 0.1524)
				(type default)
			)
			(layer "B.SilkS")
		)
		(fp_line
			(start 0.7874 -0.4064)
			(end -0.7874 -0.4064)
			(stroke
				(width 0.1524)
				(type default)
			)
			(layer "B.SilkS")
		)
		(fp_line
			(start 0.7874 0.4064)
			(end 0.7874 -0.4064)
			(stroke
				(width 0.1524)
				(type default)
			)
			(layer "B.SilkS")
		)
		(fp_line
			(start -0.67945 -0.3048)
			(end -0.67945 0.3048)
			(stroke
				(width 0.1)
				(type default)
			)
			(layer "B.Fab")
		)
		(fp_line
			(start -0.67945 0.3048)
			(end -0.120396 0.3048)
			(stroke
				(width 0.1)
				(type default)
			)
			(layer "B.Fab")
		)
		(fp_line
			(start -0.12065 -0.3048)
			(end -0.67945 -0.3048)
			(stroke
				(width 0.1)
				(type default)
			)
			(layer "B.Fab")
		)
		(fp_line
			(start -0.12065 -0.2794)
			(end -0.12065 -0.3048)
			(stroke
				(width 0.1)
				(type default)
			)
			(layer "B.Fab")
		)
		(fp_line
			(start -0.120396 0.2794)
			(end 0.12065 0.2794)
			(stroke
				(width 0.1)
				(type default)
			)
			(layer "B.Fab")
		)
		(fp_line
			(start -0.120396 0.3048)
			(end -0.120396 0.2794)
			(stroke
				(width 0.1)
				(type default)
			)
			(layer "B.Fab")
		)
		(fp_line
			(start 0.12065 -0.305054)
			(end 0.12065 -0.2794)
			(stroke
				(width 0.1)
				(type default)
			)
			(layer "B.Fab")
		)
		(fp_line
			(start 0.12065 -0.2794)
			(end -0.12065 -0.2794)
			(stroke
				(width 0.1)
				(type default)
			)
			(layer "B.Fab")
		)
		(fp_line
			(start 0.12065 0.2794)
			(end 0.12065 0.3048)
			(stroke
				(width 0.1)
				(type default)
			)
			(layer "B.Fab")
		)
		(fp_line
			(start 0.12065 0.3048)
			(end 0.67945 0.3048)
			(stroke
				(width 0.1)
				(type default)
			)
			(layer "B.Fab")
		)
		(fp_line
			(start 0.67945 -0.305054)
			(end 0.12065 -0.305054)
			(stroke
				(width 0.1)
				(type default)
			)
			(layer "B.Fab")
		)
		(fp_line
			(start 0.67945 0.3048)
			(end 0.67945 -0.305054)
			(stroke
				(width 0.1)
				(type default)
			)
			(layer "B.Fab")
		)
		(pad "1" smd circle
			(at 0.40005 0 180)
			(size 0 0)
			(layers "B.Cu" "B.Mask" "B.Paste")
			(net "PVDDCR_CPU1_P0")
		)
		(pad "2" smd circle
			(at -0.40005 0 180)
			(size 0 0)
			(layers "B.Cu" "B.Mask" "B.Paste")
			(net "GND")
		)
	)
	(footprint ""
		(layer "B.Cu")
		(at 123.611386 -257.930396)
		(property "Reference" "C3915"
			(at 0 0 0)
			(layer "B.SilkS")
			(hide yes)
			(effects
				(font
					(size 1.27 1.27)
				)
				(justify mirror)
			)
		)
		(property "Value" ""
			(at 0 0 0)
			(layer "B.Fab")
			(effects
				(font
					(size 1.27 1.27)
				)
				(justify mirror)
			)
		)
		(duplicate_pad_numbers_are_jumpers no)
		(fp_line
			(start -0.7874 -0.4064)
			(end -0.7874 0.4064)
			(stroke
				(width 0.1524)
				(type default)
			)
			(layer "B.SilkS")
		)
		(fp_line
			(start -0.7874 0.4064)
			(end 0.7874 0.4064)
			(stroke
				(width 0.1524)
				(type default)
			)
			(layer "B.SilkS")
		)
		(fp_line
			(start 0.7874 -0.4064)
			(end -0.7874 -0.4064)
			(stroke
				(width 0.1524)
				(type default)
			)
			(layer "B.SilkS")
		)
		(fp_line
			(start 0.7874 0.4064)
			(end 0.7874 -0.4064)
			(stroke
				(width 0.1524)
				(type default)
			)
			(layer "B.SilkS")
		)
		(fp_line
			(start -0.67945 -0.3048)
			(end -0.67945 0.3048)
			(stroke
				(width 0.1)
				(type default)
			)
			(layer "B.Fab")
		)
		(fp_line
			(start -0.67945 0.3048)
			(end -0.120396 0.3048)
			(stroke
				(width 0.1)
				(type default)
			)
			(layer "B.Fab")
		)
		(fp_line
			(start -0.12065 -0.3048)
			(end -0.67945 -0.3048)
			(stroke
				(width 0.1)
				(type default)
			)
			(layer "B.Fab")
		)
		(fp_line
			(start -0.12065 -0.2794)
			(end -0.12065 -0.3048)
			(stroke
				(width 0.1)
				(type default)
			)
			(layer "B.Fab")
		)
		(fp_line
			(start -0.120396 0.2794)
			(end 0.12065 0.2794)
			(stroke
				(width 0.1)
				(type default)
			)
			(layer "B.Fab")
		)
		(fp_line
			(start -0.120396 0.3048)
			(end -0.120396 0.2794)
			(stroke
				(width 0.1)
				(type default)
			)
			(layer "B.Fab")
		)
		(fp_line
			(start 0.12065 -0.305054)
			(end 0.12065 -0.2794)
			(stroke
				(width 0.1)
				(type default)
			)
			(layer "B.Fab")
		)
		(fp_line
			(start 0.12065 -0.2794)
			(end -0.12065 -0.2794)
			(stroke
				(width 0.1)
				(type default)
			)
			(layer "B.Fab")
		)
		(fp_line
			(start 0.12065 0.2794)
			(end 0.12065 0.3048)
			(stroke
				(width 0.1)
				(type default)
			)
			(layer "B.Fab")
		)
		(fp_line
			(start 0.12065 0.3048)
			(end 0.67945 0.3048)
			(stroke
				(width 0.1)
				(type default)
			)
			(layer "B.Fab")
		)
		(fp_line
			(start 0.67945 -0.305054)
			(end 0.12065 -0.305054)
			(stroke
				(width 0.1)
				(type default)
			)
			(layer "B.Fab")
		)
		(fp_line
			(start 0.67945 0.3048)
			(end 0.67945 -0.305054)
			(stroke
				(width 0.1)
				(type default)
			)
			(layer "B.Fab")
		)
		(pad "1" smd circle
			(at 0.40005 0 180)
			(size 0 0)
			(layers "B.Cu" "B.Mask" "B.Paste")
			(net "PVDDCR_SOC_P1")
		)
		(pad "2" smd circle
			(at -0.40005 0 180)
			(size 0 0)
			(layers "B.Cu" "B.Mask" "B.Paste")
			(net "GND")
		)
	)
)
